# S9S_MB_2U (Grand Teton) — schematic netlist excerpt (pin names and nets, part order shuffled) for the footprints in the layout excerpt that follows; sources: Cadence DE-HDL packaged netlist, KiCad conversion of 03242023_DA0F0TMBIJ0_F0T_Motherboard_J_brd_V01_OCP.brd

R478  Q_RES  4.7K 1% CHIP  pkg 0402LF  page 190 : A = P3V3_AUX ; B = PCIE_M2_SSD0_PRSNT_N
PR3966  Q_RES  10 1% EMPTY  pkg 0402LF  page 192 : A = P12V_AUX ; B = P12V_E1S_VCC_0

(kicad_pcb
	(version 20260206)
	(generator "pcbnew")
	(generator_version "10.0")
	(general
		(thickness 1.6)
		(legacy_teardrops no)
	)
	(paper "A4")
	(title_block
		(title "03242023_DA0F0TMBIJ0_F0T_Motherboard_J_brd_V01_OCP.brd")
		(comment 1 "Grand Teton / footprints 3367-3368 of 6105")
	)
	(layers
		(0 "F.Cu" signal "TOP")
		(4 "In1.Cu" signal "GND")
		(6 "In2.Cu" signal "IN1")
		(8 "In3.Cu" signal "GND1")
		(10 "In4.Cu" signal "IN2")
		(12 "In5.Cu" signal "GND2")
		(14 "In6.Cu" signal "IN3")
		(16 "In7.Cu" signal "GND3")
		(18 "In8.Cu" signal "VCC")
		(20 "In9.Cu" signal "VCC1")
		(22 "In10.Cu" signal "GND4")
		(24 "In11.Cu" signal "IN4")
		(26 "In12.Cu" signal "GND5")
		(28 "In13.Cu" signal "IN5")
		(30 "In14.Cu" signal "GND6")
		(32 "In15.Cu" signal "IN6")
		(34 "In16.Cu" signal "GND7")
		(2 "B.Cu" signal "BOTTOM")
		(9 "F.Adhes" user "F.Adhesive")
		(11 "B.Adhes" user "B.Adhesive")
		(13 "F.Paste" user "Package Geometry/Pastemask Top")
		(15 "B.Paste" user "Package Geometry/Pastemask Bottom")
		(5 "F.SilkS" user "Ref Des/Silkscreen Top")
		(7 "B.SilkS" user "Ref Des/Silkscreen Bottom")
		(1 "F.Mask" user "Board Geometry/Soldermask Top")
		(3 "B.Mask" user "Board Geometry/Soldermask Bottom")
		(17 "Dwgs.User" user "User.Drawings")
		(19 "Cmts.User" user "User.Comments")
		(21 "Eco1.User" user "User.Eco1")
		(23 "Eco2.User" user "User.Eco2")
		(25 "Edge.Cuts" user "Board Geometry/Outline")
		(27 "Margin" user)
		(31 "F.CrtYd" user "Package Geometry/Place Bound Top")
		(29 "B.CrtYd" user "Package Geometry/Place Bound Bottom")
		(35 "F.Fab" user "Ref Des/Assembly Top")
		(33 "B.Fab" user "Ref Des/Assembly Bottom")
	)
	(footprint ""
		(layer "F.Cu")
		(at 256.889504 -42.488612 180)
		(property "Reference" "PR3966"
			(at 0 0 180)
			(layer "F.SilkS")
			(hide yes)
			(effects
				(font
					(size 1.27 1.27)
				)
			)
		)
		(property "Value" ""
			(at 0 0 180)
			(layer "F.Fab")
			(effects
				(font
					(size 1.27 1.27)
				)
			)
		)
		(duplicate_pad_numbers_are_jumpers no)
		(fp_line
			(start 0.7874 0.4064)
			(end -0.7874 0.4064)
			(stroke
				(width 0.1524)
				(type default)
			)
			(layer "F.SilkS")
		)
		(fp_line
			(start 0.7874 -0.4064)
			(end 0.7874 0.4064)
			(stroke
				(width 0.1524)
				(type default)
			)
			(layer "F.SilkS")
		)
		(fp_line
			(start -0.7874 0.4064)
			(end -0.7874 -0.4064)
			(stroke
				(width 0.1524)
				(type default)
			)
			(layer "F.SilkS")
		)
		(fp_line
			(start -0.7874 -0.4064)
			(end 0.7874 -0.4064)
			(stroke
				(width 0.1524)
				(type default)
			)
			(layer "F.SilkS")
		)
		(fp_line
			(start 0.67945 0.3048)
			(end 0.120396 0.3048)
			(stroke
				(width 0.1)
				(type default)
			)
			(layer "F.Fab")
		)
		(fp_line
			(start 0.67945 -0.3048)
			(end 0.67945 0.3048)
			(stroke
				(width 0.1)
				(type default)
			)
			(layer "F.Fab")
		)
		(fp_line
			(start 0.12065 -0.2794)
			(end 0.12065 -0.3048)
			(stroke
				(width 0.1)
				(type default)
			)
			(layer "F.Fab")
		)
		(fp_line
			(start 0.12065 -0.3048)
			(end 0.67945 -0.3048)
			(stroke
				(width 0.1)
				(type default)
			)
			(layer "F.Fab")
		)
		(fp_line
			(start 0.120396 0.3048)
			(end 0.120396 0.2794)
			(stroke
				(width 0.1)
				(type default)
			)
			(layer "F.Fab")
		)
		(fp_line
			(start 0.120396 0.2794)
			(end -0.12065 0.2794)
			(stroke
				(width 0.1)
				(type default)
			)
			(layer "F.Fab")
		)
		(fp_line
			(start -0.12065 0.3048)
			(end -0.67945 0.3048)
			(stroke
				(width 0.1)
				(type default)
			)
			(layer "F.Fab")
		)
		(fp_line
			(start -0.12065 0.2794)
			(end -0.12065 0.3048)
			(stroke
				(width 0.1)
				(type default)
			)
			(layer "F.Fab")
		)
		(fp_line
			(start -0.12065 -0.2794)
			(end 0.12065 -0.2794)
			(stroke
				(width 0.1)
				(type default)
			)
			(layer "F.Fab")
		)
		(fp_line
			(start -0.12065 -0.305054)
			(end -0.12065 -0.2794)
			(stroke
				(width 0.1)
				(type default)
			)
			(layer "F.Fab")
		)
		(fp_line
			(start -0.67945 0.3048)
			(end -0.67945 -0.305054)
			(stroke
				(width 0.1)
				(type default)
			)
			(layer "F.Fab")
		)
		(fp_line
			(start -0.67945 -0.305054)
			(end -0.12065 -0.305054)
			(stroke
				(width 0.1)
				(type default)
			)
			(layer "F.Fab")
		)
		(pad "1" smd circle
			(at -0.40005 0 180)
			(size 0 0)
			(layers "F.Cu" "F.Mask" "F.Paste")
			(net "P12V_AUX")
		)
		(pad "2" smd circle
			(at 0.40005 0 180)
			(size 0 0)
			(layers "F.Cu" "F.Mask" "F.Paste")
			(net "P12V_E1S_VCC_0")
		)
	)
	(footprint ""
		(layer "F.Cu")
		(at 180.77688 -56.352948 180)
		(property "Reference" "R478"
			(at 0 0 180)
			(layer "F.SilkS")
			(hide yes)
			(effects
				(font
					(size 1.27 1.27)
				)
			)
		)
		(property "Value" ""
			(at 0 0 180)
			(layer "F.Fab")
			(effects
				(font
					(size 1.27 1.27)
				)
			)
		)
		(duplicate_pad_numbers_are_jumpers no)
		(fp_line
			(start 0.7874 0.4064)
			(end -0.7874 0.4064)
			(stroke
				(width 0.1524)
				(type default)
			)
			(layer "F.SilkS")
		)
		(fp_line
			(start 0.7874 -0.4064)
			(end 0.7874 0.4064)
			(stroke
				(width 0.1524)
				(type default)
			)
			(layer "F.SilkS")
		)
		(fp_line
			(start -0.7874 0.4064)
			(end -0.7874 -0.4064)
			(stroke
				(width 0.1524)
				(type default)
			)
			(layer "F.SilkS")
		)
		(fp_line
			(start -0.7874 -0.4064)
			(end 0.7874 -0.4064)
			(stroke
				(width 0.1524)
				(type default)
			)
			(layer "F.SilkS")
		)
		(fp_line
			(start 0.67945 0.3048)
			(end 0.120396 0.3048)
			(stroke
				(width 0.1)
				(type default)
			)
			(layer "F.Fab")
		)
		(fp_line
			(start 0.67945 -0.3048)
			(end 0.67945 0.3048)
			(stroke
				(width 0.1)
				(type default)
			)
			(layer "F.Fab")
		)
		(fp_line
			(start 0.12065 -0.2794)
			(end 0.12065 -0.3048)
			(stroke
				(width 0.1)
				(type default)
			)
			(layer "F.Fab")
		)
		(fp_line
			(start 0.12065 -0.3048)
			(end 0.67945 -0.3048)
			(stroke
				(width 0.1)
				(type default)
			)
			(layer "F.Fab")
		)
		(fp_line
			(start 0.120396 0.3048)
			(end 0.120396 0.2794)
			(stroke
				(width 0.1)
				(type default)
			)
			(layer "F.Fab")
		)
		(fp_line
			(start 0.120396 0.2794)
			(end -0.12065 0.2794)
			(stroke
				(width 0.1)
				(type default)
			)
			(layer "F.Fab")
		)
		(fp_line
			(start -0.12065 0.3048)
			(end -0.67945 0.3048)
			(stroke
				(width 0.1)
				(type default)
			)
			(layer "F.Fab")
		)
		(fp_line
			(start -0.12065 0.2794)
			(end -0.12065 0.3048)
			(stroke
				(width 0.1)
				(type default)
			)
			(layer "F.Fab")
		)
		(fp_line
			(start -0.12065 -0.2794)
			(end 0.12065 -0.2794)
			(stroke
				(width 0.1)
				(type default)
			)
			(layer "F.Fab")
		)
		(fp_line
			(start -0.12065 -0.305054)
			(end -0.12065 -0.2794)
			(stroke
				(width 0.1)
				(type default)
			)
			(layer "F.Fab")
		)
		(fp_line
			(start -0.67945 0.3048)
			(end -0.67945 -0.305054)
			(stroke
				(width 0.1)
				(type default)
			)
			(layer "F.Fab")
		)
		(fp_line
			(start -0.67945 -0.305054)
			(end -0.12065 -0.305054)
			(stroke
				(width 0.1)
				(type default)
			)
			(layer "F.Fab")
		)
		(pad "1" smd circle
			(at -0.40005 0 180)
			(size 0 0)
			(layers "F.Cu" "F.Mask" "F.Paste")
			(net "P3V3_AUX")
		)
		(pad "2" smd circle
			(at 0.40005 0 180)
			(size 0 0)
			(layers "F.Cu" "F.Mask" "F.Paste")
			(net "PCIE_M2_SSD0_PRSNT_N")
		)
	)
)
